# BASEBOARD_FAB2 (Tioga Pass) — schematic netlist excerpt (pin names and nets, part order shuffled) for the footprints in the layout excerpt that follows; sources: Cadence DE-HDL packaged netlist, KiCad conversion of Wiwynn_Tioga_Pass_MB.brd

J9M1  SCONN288_H44441003  SCONN  pkg PIP  page 84
  \12v\(1)  = P12V_NVDIMM_KLM
  VSS(93)  = GND
  DQ(4)  = M_K_DQ<4>
  VSS(92)  = GND
  DQ(0)  = M_K_DQ<0>
  VSS(91)  = GND
  DQS9P  = M_K_DQS_DP<9>
  DQS9N  = M_K_DQS_DN<9>
  VSS(90)  = GND
  DQ(6)  = M_K_DQ<6>
  VSS(89)  = GND
  DQ(2)  = M_K_DQ<2>
  VSS(88)  = GND
  DQ(12)  = M_K_DQ<12>
  VSS(87)  = GND
  DQ(8)  = M_K_DQ<8>
  VSS(86)  = GND
  DQS10P  = M_K_DQS_DP<10>
  DQS10N  = M_K_DQS_DN<10>
  VSS(85)  = GND
  DQ(14)  = M_K_DQ<14>
  VSS(84)  = GND
  DQ(10)  = M_K_DQ<10>
  VSS(83)  = GND
  DQ(20)  = M_K_DQ<20>
  VSS(82)  = GND
  DQ(16)  = M_K_DQ<16>
  VSS(81)  = GND
  DQS11P  = M_K_DQS_DP<11>
  DQS11N  = M_K_DQS_DN<11>
  VSS(80)  = GND
  DQ(22)  = M_K_DQ<22>
  VSS(79)  = GND
  DQ(18)  = M_K_DQ<18>
  VSS(78)  = GND
  DQ(28)  = M_K_DQ<28>
  VSS(77)  = GND
  DQ(24)  = M_K_DQ<24>
  VSS(76)  = GND
  DQS12P  = M_K_DQS_DP<12>
  DQS12N  = M_K_DQS_DN<12>
  VSS(75)  = GND
  DQ(30)  = M_K_DQ<30>
  VSS(74)  = GND
  DQ(26)  = M_K_DQ<26>
  VSS(73)  = GND
  CB(4)  = M_K_ECC<4>
  VSS(72)  = GND
  CB(0)  = M_K_ECC<0>
  VSS(71)  = GND
  DQS17P  = M_K_DQS_DP<17>
  DQS17N  = M_K_DQS_DN<17>
  VSS(70)  = GND
  CB(6)  = M_K_ECC<6>
  VSS(69)  = GND
  CB(2)  = M_K_ECC<2>
  VSS(68)  = GND
  RESET_N  = M_KLM_RST_N
  VDD(25)  = PVDDQ_KLM
  CKE(0)  = M_K_CKE<2>
  VDD(24)  = PVDDQ_KLM
  ACT_N  = M_K_ACT_N
  BG(0)  = M_K_BG<0>
  VDD(23)  = PVDDQ_KLM
  A12  = M_K_MA<12>
  A9  = M_K_MA<9>
  VDD(22)  = PVDDQ_KLM
  A8  = M_K_MA<8>
  A6  = M_K_MA<6>
  VDD(21)  = PVDDQ_KLM
  A3  = M_K_MA<3>
  A1  = M_K_MA<1>
  VDD(20)  = PVDDQ_KLM
  CK0P  = M_K_CLK_DP<2>
  CK0N  = M_K_CLK_DN<2>
  VDD(19)  = PVDDQ_KLM
  VTT(1)  = PVTT_KLM
  EVENT_N  = FM_DIMM_EVENT_COD_N
  A0  = M_K_MA<0>
  VDD(18)  = PVDDQ_KLM
  BA(0)  = M_K_BA<0>
  A16_RAS_N  = M_K_MA<16>
  VDD(17)  = PVDDQ_KLM
  S0_N  = M_K_CS_N<4>
  VDD(16)  = PVDDQ_KLM
  A15_CAS_N  = M_K_MA<15>
  ODT(0)  = M_K_ODT<2>
  VDD(15)  = PVDDQ_KLM
  S1_N  = M_K_CS_N<5>
  VDD(14)  = PVDDQ_KLM
  ODT(1)  = M_K_ODT<3>
  VDD(13)  = PVDDQ_KLM
  S2_N_C(0)  = M_K_CS_N<6>
  VSS(67)  = GND
  DQ(36)  = M_K_DQ<36>
  VSS(66)  = GND
  DQ(32)  = M_K_DQ<32>
  VSS(65)  = GND
  DQS13P  = M_K_DQS_DP<13>
  DQS13N  = M_K_DQS_DN<13>
  VSS(64)  = GND
  DQ(38)  = M_K_DQ<38>
  VSS(63)  = GND
  DQ(34)  = M_K_DQ<34>
  VSS(62)  = GND
  DQ(44)  = M_K_DQ<44>
  VSS(61)  = GND
  DQ(40)  = M_K_DQ<40>
  VSS(60)  = GND
  DQS14P  = M_K_DQS_DP<14>
  DQS14N  = M_K_DQS_DN<14>
  VSS(59)  = GND
  DQ(46)  = M_K_DQ<46>
  VSS(58)  = GND
  DQ(42)  = M_K_DQ<42>
  VSS(57)  = GND
  DQ(52)  = M_K_DQ<52>
  VSS(56)  = GND
  DQ(48)  = M_K_DQ<48>
  VSS(55)  = GND
  DQS15P  = M_K_DQS_DP<15>
  DQS15N  = M_K_DQS_DN<15>
  VSS(54)  = GND
  DQ(54)  = M_K_DQ<54>
  VSS(53)  = GND
  DQ(50)  = M_K_DQ<50>
  VSS(52)  = GND
  DQ(60)  = M_K_DQ<60>
  VSS(51)  = GND
  DQ(56)  = M_K_DQ<56>
  VSS(50)  = GND
  DQS16P  = M_K_DQS_DP<16>
  DQS16N  = M_K_DQS_DN<16>
  VSS(49)  = GND
  DQ(62)  = M_K_DQ<62>
  VSS(48)  = GND
  DQ(58)  = M_K_DQ<58>
  VSS(47)  = GND
  SA(0)  = PVPP_KLM
  SA(1)  = GND
  SCL  = SMB_DDR_KLM_VPP_SCL
  VPP(4)  = PVPP_KLM
  VPP(3)  = PVPP_KLM
  RFU(2)  = TP_CH_K_DIMM0_RFU_2
  \12v\(0)  = P12V_NVDIMM_KLM
  VREFCA  = M_K_VREF
  VSS(46)  = GND
  DQ(5)  = M_K_DQ<5>
  VSS(45)  = GND
  DQ(1)  = M_K_DQ<1>
  VSS(44)  = GND
  DQS0N  = M_K_DQS_DN<0>
  DQS0P  = M_K_DQS_DP<0>
  VSS(43)  = GND
  DQ(7)  = M_K_DQ<7>
  VSS(42)  = GND
  DQ(3)  = M_K_DQ<3>
  VSS(41)  = GND
  DQ(13)  = M_K_DQ<13>
  VSS(40)  = GND
  DQ(9)  = M_K_DQ<9>
  VSS(39)  = GND
  DQS1N  = M_K_DQS_DN<1>
  DQS1P  = M_K_DQS_DP<1>
  VSS(38)  = GND
  DQ(15)  = M_K_DQ<15>
  VSS(37)  = GND
  DQ(11)  = M_K_DQ<11>
  VSS(36)  = GND
  DQ(21)  = M_K_DQ<21>
  VSS(35)  = GND
  DQ(17)  = M_K_DQ<17>
  VSS(34)  = GND
  DQS2N  = M_K_DQS_DN<2>
  DQS2P  = M_K_DQS_DP<2>
  VSS(33)  = GND
  DQ(23)  = M_K_DQ<23>
  VSS(32)  = GND
  DQ(19)  = M_K_DQ<19>
  VSS(31)  = GND
  DQ(29)  = M_K_DQ<29>
  VSS(30)  = GND
  DQ(25)  = M_K_DQ<25>
  VSS(29)  = GND
  DQS3N  = M_K_DQS_DN<3>
  DQS3P  = M_K_DQS_DP<3>
  VSS(28)  = GND
  DQ(31)  = M_K_DQ<31>
  VSS(27)  = GND
  DQ(27)  = M_K_DQ<27>
  VSS(26)  = GND
  CB(5)  = M_K_ECC<5>
  VSS(25)  = GND
  CB(1)  = M_K_ECC<1>
  VSS(24)  = GND
  DQS8N  = M_K_DQS_DN<8>
  DQS8P  = M_K_DQS_DP<8>
  VSS(23)  = GND
  CB(7)  = M_K_ECC<7>
  VSS(22)  = GND
  CB(3)  = M_K_ECC<3>
  VSS(21)  = GND
  CKE(1)  = M_K_CKE<3>
  VDD(12)  = PVDDQ_KLM
  RFU(0)  = TP_CH_K_DIMM0_RFU_0
  VDD(11)  = PVDDQ_KLM
  BG(1)  = M_K_BG<1>
  ALERT_N  = M_K_ALERT_N
  VDD(10)  = PVDDQ_KLM
  A11  = M_K_MA<11>
  A7  = M_K_MA<7>
  VDD(9)  = PVDDQ_KLM
  A5  = M_K_MA<5>
  A4  = M_K_MA<4>
  VDD(8)  = PVDDQ_KLM
  A2  = M_K_MA<2>
  VDD(7)  = PVDDQ_KLM
  CK1P  = M_K_CLK_DP<3>
  CK1N  = M_K_CLK_DN<3>
  VDD(6)  = PVDDQ_KLM
  VTT(0)  = PVTT_KLM
  PAR  = M_K_PAR
  VDD(5)  = PVDDQ_KLM
  BA(1)  = M_K_BA<1>
  A10  = M_K_MA<10>
  VDD(4)  = PVDDQ_KLM
  RFU(1)  = TP_CH_K_DIMM0_RFU_1
  A14_WE_N  = M_K_MA<14>
  VDD(3)  = PVDDQ_KLM
  SAVE_N_NC  = FM_ADR_COMPLETE_KLM_N
  VDD(2)  = PVDDQ_KLM
  A13  = M_K_MA<13>
  VDD(1)  = PVDDQ_KLM
  A17  = M_K_MA<17>
  C(2)  = M_K_C<2>
  VDD(0)  = PVDDQ_KLM
  S3_N_C(1)  = M_K_CS_N<7>
  SA(2)  = GND
  VSS(20)  = GND
  DQ(37)  = M_K_DQ<37>
  VSS(19)  = GND
  DQ(33)  = M_K_DQ<33>
  VSS(18)  = GND
  DQS4N  = M_K_DQS_DN<4>
  DQS4P  = M_K_DQS_DP<4>
  VSS(17)  = GND
  DQ(39)  = M_K_DQ<39>
  VSS(16)  = GND
  DQ(35)  = M_K_DQ<35>
  VSS(15)  = GND
  DQ(45)  = M_K_DQ<45>
  VSS(14)  = GND
  DQ(41)  = M_K_DQ<41>
  VSS(13)  = GND
  DQS5N  = M_K_DQS_DN<5>
  DQS5P  = M_K_DQS_DP<5>
  VSS(12)  = GND
  DQ(47)  = M_K_DQ<47>
  VSS(11)  = GND
  DQ(43)  = M_K_DQ<43>
  VSS(10)  = GND
  DQ(53)  = M_K_DQ<53>
  VSS(9)  = GND
  DQ(49)  = M_K_DQ<49>
  VSS(8)  = GND
  DQS6N  = M_K_DQS_DN<6>
  DQS6P  = M_K_DQS_DP<6>
  VSS(7)  = GND
  DQ(55)  = M_K_DQ<55>
  VSS(6)  = GND
  DQ(51)  = M_K_DQ<51>
  VSS(5)  = GND
  DQ(61)  = M_K_DQ<61>
  VSS(4)  = GND
  DQ(57)  = M_K_DQ<57>
  VSS(3)  = GND
  DQS7N  = M_K_DQS_DN<7>
  DQS7P  = M_K_DQS_DP<7>
  VSS(2)  = GND
  DQ(63)  = M_K_DQ<63>
  VSS(1)  = GND
  DQ(59)  = M_K_DQ<59>
  VSS(0)  = GND
  VDDSPD  = PVPP_KLM
  SDA  = SMB_DDR_KLM_VPP_SDA
  VPP(1)  = PVPP_KLM
  VPP(0)  = PVPP_KLM
  VPP(2)  = PVPP_KLM

(kicad_pcb
	(version 20260206)
	(generator "pcbnew")
	(generator_version "10.0")
	(general
		(thickness 1.6)
		(legacy_teardrops no)
	)
	(paper "A4")
	(title_block
		(title "Wiwynn_Tioga_Pass_MB.brd")
		(comment 1 "Tioga Pass / footprint 2445 of 4770 (J9M1), pads 1-50 of 291")
	)
	(layers
		(0 "F.Cu" signal "TOP")
		(4 "In1.Cu" signal "L2GND")
		(6 "In2.Cu" signal "L3")
		(8 "In3.Cu" signal "L4GND")
		(10 "In4.Cu" signal "L5")
		(12 "In5.Cu" signal "L6GND")
		(14 "In6.Cu" signal "L7VCC")
		(16 "In7.Cu" signal "L8VCC")
		(18 "In8.Cu" signal "L9GND")
		(20 "In9.Cu" signal "L10")
		(22 "In10.Cu" signal "L11GND")
		(24 "In11.Cu" signal "L12")
		(26 "In12.Cu" signal "L13GND")
		(2 "B.Cu" signal "BOTTOM")
		(9 "F.Adhes" user "F.Adhesive")
		(11 "B.Adhes" user "B.Adhesive")
		(13 "F.Paste" user "Package Geometry/Pastemask Top")
		(15 "B.Paste" user "Package Geometry/Pastemask Bottom")
		(5 "F.SilkS" user "Ref Des/Silkscreen Top")
		(7 "B.SilkS" user "Ref Des/Silkscreen Bottom")
		(1 "F.Mask" user "Board Geometry/Soldermask Top")
		(3 "B.Mask" user "Board Geometry/Soldermask Bottom")
		(17 "Dwgs.User" user "User.Drawings")
		(19 "Cmts.User" user "User.Comments")
		(21 "Eco1.User" user "User.Eco1")
		(23 "Eco2.User" user "User.Eco2")
		(25 "Edge.Cuts" user "Board Geometry/Outline")
		(27 "Margin" user)
		(31 "F.CrtYd" user "Package Geometry/Place Bound Top")
		(29 "B.CrtYd" user "Package Geometry/Place Bound Bottom")
		(35 "F.Fab" user "Ref Des/Assembly Top")
		(33 "B.Fab" user "Ref Des/Assembly Bottom")
	)
	(footprint ""
		(layer "B.Cu")
		(at 29.699458 -132.876036 90)
		(property "Reference" "J9M1"
			(at 2.352548 37.991542 0)
			(unlocked yes)
			(layer "B.SilkS")
			(effects
				(font
					(size 0.7874 0.5842)
					(thickness 0.1524)
				)
				(justify left mirror)
			)
		)
		(property "Value" ""
			(at 0 0 90)
			(layer "B.Fab")
			(effects
				(font
					(size 1.27 1.27)
				)
				(justify mirror)
			)
		)
		(duplicate_pad_numbers_are_jumpers no)
		(pad "" thru_hole circle
			(at -2.29997 -5.649976 270)
			(size 2.8194 2.8194)
			(drill 2.4384)
			(layers "*.Cu" "*.Mask")
			(remove_unused_layers no)
			(clearance 0.127)
			(thermal_gap 0.127)
		)
		(pad "" thru_hole oval
			(at -2.29997 68.90004 270)
			(size 2.8194 1.5748)
			(drill oval 2.4384 1.1938)
			(layers "*.Cu" "*.Mask")
			(remove_unused_layers no)
			(clearance 0.127)
			(thermal_gap 0.127)
		)
		(pad "" thru_hole circle
			(at -2.29997 132.299964 270)
			(size 2.8194 2.8194)
			(drill 2.4384)
			(layers "*.Cu" "*.Mask")
			(remove_unused_layers no)
			(clearance 0.127)
			(thermal_gap 0.127)
		)
		(pad "1" smd rect
			(at 0 0 270)
			(size 1.8034 0.508)
			(layers "B.Cu" "B.Mask" "B.Paste")
			(net "P12V_NVDIMM_KLM")
		)
		(pad "2" smd rect
			(at 0 0.849884 270)
			(size 1.8034 0.508)
			(layers "B.Cu" "B.Mask" "B.Paste")
			(net "GND")
		)
		(pad "3" smd rect
			(at 0 1.700022 270)
			(size 1.8034 0.508)
			(layers "B.Cu" "B.Mask" "B.Paste")
			(net "M_K_DQ<4>")
		)
		(pad "4" smd rect
			(at 0 2.549906 270)
			(size 1.8034 0.508)
			(layers "B.Cu" "B.Mask" "B.Paste")
			(net "GND")
		)
		(pad "5" smd rect
			(at 0 3.400044 270)
			(size 1.8034 0.508)
			(layers "B.Cu" "B.Mask" "B.Paste")
			(net "M_K_DQ<0>")
		)
		(pad "6" smd rect
			(at 0 4.249928 270)
			(size 1.8034 0.508)
			(layers "B.Cu" "B.Mask" "B.Paste")
			(net "GND")
		)
		(pad "7" smd rect
			(at 0 5.100066 270)
			(size 1.8034 0.508)
			(layers "B.Cu" "B.Mask" "B.Paste")
			(net "M_K_DQS_DP<9>")
		)
		(pad "8" smd rect
			(at 0 5.94995 270)
			(size 1.8034 0.508)
			(layers "B.Cu" "B.Mask" "B.Paste")
			(net "M_K_DQS_DN<9>")
		)
		(pad "9" smd rect
			(at 0 6.800088 270)
			(size 1.8034 0.508)
			(layers "B.Cu" "B.Mask" "B.Paste")
			(net "GND")
		)
		(pad "10" smd rect
			(at 0 7.649972 270)
			(size 1.8034 0.508)
			(layers "B.Cu" "B.Mask" "B.Paste")
			(net "M_K_DQ<6>")
		)
		(pad "11" smd rect
			(at 0 8.50011 270)
			(size 1.8034 0.508)
			(layers "B.Cu" "B.Mask" "B.Paste")
			(net "GND")
		)
		(pad "12" smd rect
			(at 0 9.349994 270)
			(size 1.8034 0.508)
			(layers "B.Cu" "B.Mask" "B.Paste")
			(net "M_K_DQ<2>")
		)
		(pad "13" smd rect
			(at 0 10.199878 270)
			(size 1.8034 0.508)
			(layers "B.Cu" "B.Mask" "B.Paste")
			(net "GND")
		)
		(pad "14" smd rect
			(at 0 11.050016 270)
			(size 1.8034 0.508)
			(layers "B.Cu" "B.Mask" "B.Paste")
			(net "M_K_DQ<12>")
		)
		(pad "15" smd rect
			(at 0 11.8999 270)
			(size 1.8034 0.508)
			(layers "B.Cu" "B.Mask" "B.Paste")
			(net "GND")
		)
		(pad "16" smd rect
			(at 0 12.750038 270)
			(size 1.8034 0.508)
			(layers "B.Cu" "B.Mask" "B.Paste")
			(net "M_K_DQ<8>")
		)
		(pad "17" smd rect
			(at 0 13.599922 270)
			(size 1.8034 0.508)
			(layers "B.Cu" "B.Mask" "B.Paste")
			(net "GND")
		)
		(pad "18" smd rect
			(at 0 14.45006 270)
			(size 1.8034 0.508)
			(layers "B.Cu" "B.Mask" "B.Paste")
			(net "M_K_DQS_DP<10>")
		)
		(pad "19" smd rect
			(at 0 15.299944 270)
			(size 1.8034 0.508)
			(layers "B.Cu" "B.Mask" "B.Paste")
			(net "M_K_DQS_DN<10>")
		)
		(pad "20" smd rect
			(at 0 16.150082 270)
			(size 1.8034 0.508)
			(layers "B.Cu" "B.Mask" "B.Paste")
			(net "GND")
		)
		(pad "21" smd rect
			(at 0 16.999966 270)
			(size 1.8034 0.508)
			(layers "B.Cu" "B.Mask" "B.Paste")
			(net "M_K_DQ<14>")
		)
		(pad "22" smd rect
			(at 0 17.850104 270)
			(size 1.8034 0.508)
			(layers "B.Cu" "B.Mask" "B.Paste")
			(net "GND")
		)
		(pad "23" smd rect
			(at 0 18.699988 270)
			(size 1.8034 0.508)
			(layers "B.Cu" "B.Mask" "B.Paste")
			(net "M_K_DQ<10>")
		)
		(pad "24" smd rect
			(at 0 19.550126 270)
			(size 1.8034 0.508)
			(layers "B.Cu" "B.Mask" "B.Paste")
			(net "GND")
		)
		(pad "25" smd rect
			(at 0 20.40001 270)
			(size 1.8034 0.508)
			(layers "B.Cu" "B.Mask" "B.Paste")
			(net "M_K_DQ<20>")
		)
		(pad "26" smd rect
			(at 0 21.249894 270)
			(size 1.8034 0.508)
			(layers "B.Cu" "B.Mask" "B.Paste")
			(net "GND")
		)
		(pad "27" smd rect
			(at 0 22.100032 270)
			(size 1.8034 0.508)
			(layers "B.Cu" "B.Mask" "B.Paste")
			(net "M_K_DQ<16>")
		)
		(pad "28" smd rect
			(at 0 22.949916 270)
			(size 1.8034 0.508)
			(layers "B.Cu" "B.Mask" "B.Paste")
			(net "GND")
		)
		(pad "29" smd rect
			(at 0 23.800054 270)
			(size 1.8034 0.508)
			(layers "B.Cu" "B.Mask" "B.Paste")
			(net "M_K_DQS_DP<11>")
		)
		(pad "30" smd rect
			(at 0 24.649938 270)
			(size 1.8034 0.508)
			(layers "B.Cu" "B.Mask" "B.Paste")
			(net "M_K_DQS_DN<11>")
		)
		(pad "31" smd rect
			(at 0 25.500076 270)
			(size 1.8034 0.508)
			(layers "B.Cu" "B.Mask" "B.Paste")
			(net "GND")
		)
		(pad "32" smd rect
			(at 0 26.34996 270)
			(size 1.8034 0.508)
			(layers "B.Cu" "B.Mask" "B.Paste")
			(net "M_K_DQ<22>")
		)
		(pad "33" smd rect
			(at 0 27.200098 270)
			(size 1.8034 0.508)
			(layers "B.Cu" "B.Mask" "B.Paste")
			(net "GND")
		)
		(pad "34" smd rect
			(at 0 28.049982 270)
			(size 1.8034 0.508)
			(layers "B.Cu" "B.Mask" "B.Paste")
			(net "M_K_DQ<18>")
		)
		(pad "35" smd rect
			(at 0 28.90012 270)
			(size 1.8034 0.508)
			(layers "B.Cu" "B.Mask" "B.Paste")
			(net "GND")
		)
		(pad "36" smd rect
			(at 0 29.750004 270)
			(size 1.8034 0.508)
			(layers "B.Cu" "B.Mask" "B.Paste")
			(net "M_K_DQ<28>")
		)
		(pad "37" smd rect
			(at 0 30.599888 270)
			(size 1.8034 0.508)
			(layers "B.Cu" "B.Mask" "B.Paste")
			(net "GND")
		)
		(pad "38" smd rect
			(at 0 31.450026 270)
			(size 1.8034 0.508)
			(layers "B.Cu" "B.Mask" "B.Paste")
			(net "M_K_DQ<24>")
		)
		(pad "39" smd rect
			(at 0 32.29991 270)
			(size 1.8034 0.508)
			(layers "B.Cu" "B.Mask" "B.Paste")
			(net "GND")
		)
		(pad "40" smd rect
			(at 0 33.150048 270)
			(size 1.8034 0.508)
			(layers "B.Cu" "B.Mask" "B.Paste")
			(net "M_K_DQS_DP<12>")
		)
		(pad "41" smd rect
			(at 0 33.999932 270)
			(size 1.8034 0.508)
			(layers "B.Cu" "B.Mask" "B.Paste")
			(net "M_K_DQS_DN<12>")
		)
		(pad "42" smd rect
			(at 0 34.85007 270)
			(size 1.8034 0.508)
			(layers "B.Cu" "B.Mask" "B.Paste")
			(net "GND")
		)
		(pad "43" smd rect
			(at 0 35.699954 270)
			(size 1.8034 0.508)
			(layers "B.Cu" "B.Mask" "B.Paste")
			(net "M_K_DQ<30>")
		)
		(pad "44" smd rect
			(at 0 36.550092 270)
			(size 1.8034 0.508)
			(layers "B.Cu" "B.Mask" "B.Paste")
			(net "GND")
		)
		(pad "45" smd rect
			(at 0 37.399976 270)
			(size 1.8034 0.508)
			(layers "B.Cu" "B.Mask" "B.Paste")
			(net "M_K_DQ<26>")
		)
		(pad "46" smd rect
			(at 0 38.250114 270)
			(size 1.8034 0.508)
			(layers "B.Cu" "B.Mask" "B.Paste")
			(net "GND")
		)
		(pad "47" smd rect
			(at 0 39.099998 270)
			(size 1.8034 0.508)
			(layers "B.Cu" "B.Mask" "B.Paste")
			(net "M_K_ECC<4>")
		)
	)
)
